FILE_TYPE = CONNECTIVITY;
{Allegro Design Entry HDL 17.4-2019 S026 (4007227) 1/17/2022}
"PAGE_NUMBER" = 353;
0"NC";
1"P5E_CPU1_P0_TX_C_DN<15:8>";
2"P5E_CPU1_P0_TX_C_DP<15:8>";
3"P5E_CPU1_P0_TX_DN<15:8>";
4"P5E_CPU1_P0_TX_DP<15:8>";
5"P5E_CPU1_P0_TX_DP<7:0>";
6"P5E_CPU1_P0_TX_DN<7:0>";
7"P5E_CPU0_G3_TX_C_DP<7:0>";
8"P5E_CPU0_G3_TX_DP<15:8>";
9"P5E_CPU0_G3_TX_C_DP<15:8>";
10"P5E_CPU1_P0_TX_C_DP<7:0>";
11"P5E_CPU1_P0_TX_C_DN<7:0>";
12"P5E_CPU0_G3_TX_DP<7:0>";
13"P5E_CPU0_G3_TX_C_DN<7:0>";
14"P5E_CPU0_G3_TX_DN<7:0>";
15"P5E_CPU0_G3_TX_DN<15:8>";
16"P5E_CPU0_G3_TX_C_DN<15:8>";
17"P5E_CPU0_G3_TX_DN<6>";
18"P5E_CPU1_P0_TX_C_DP<15>";
19"P5E_CPU1_P0_TX_C_DP<14>";
20"P5E_CPU1_P0_TX_C_DP<13>";
21"P5E_CPU1_P0_TX_C_DN<12>";
22"P5E_CPU1_P0_TX_C_DN<11>";
23"P5E_CPU1_P0_TX_C_DP<9>";
24"P5E_CPU1_P0_TX_C_DP<8>";
25"P5E_CPU1_P0_TX_C_DP<5>";
26"P5E_CPU1_P0_TX_C_DP<1>";
27"P5E_CPU1_P0_TX_DP<7>";
28"P5E_CPU1_P0_TX_DN<7>";
29"P5E_CPU1_P0_TX_C_DN<5>";
30"P5E_CPU1_P0_TX_C_DP<4>";
31"P5E_CPU1_P0_TX_C_DN<15>";
32"P5E_CPU1_P0_TX_C_DN<14>";
33"P5E_CPU1_P0_TX_C_DN<13>";
34"P5E_CPU1_P0_TX_C_DP<12>";
35"P5E_CPU1_P0_TX_C_DN<7>";
36"P5E_CPU1_P0_TX_C_DP<7>";
37"P5E_CPU1_P0_TX_C_DP<6>";
38"P5E_CPU1_P0_TX_C_DN<6>";
39"P5E_CPU1_P0_TX_C_DN<4>";
40"P5E_CPU1_P0_TX_DN<15>";
41"P5E_CPU1_P0_TX_DN<14>";
42"P5E_CPU1_P0_TX_DN<13>";
43"P5E_CPU1_P0_TX_DP<15>";
44"P5E_CPU1_P0_TX_DP<14>";
45"P5E_CPU1_P0_TX_DN<12>";
46"P5E_CPU1_P0_TX_DN<10>";
47"P5E_CPU1_P0_TX_DN<11>";
48"P5E_CPU1_P0_TX_DP<12>";
49"P5E_CPU1_P0_TX_DN<9>";
50"P5E_CPU1_P0_TX_DP<10>";
51"P5E_CPU1_P0_TX_DN<6>";
52"P5E_CPU1_P0_TX_DN<5>";
53"P5E_CPU1_P0_TX_DN<4>";
54"P5E_CPU1_P0_TX_DN<1>";
55"P5E_CPU1_P0_TX_DN<0>";
56"P5E_CPU1_P0_TX_DP<3>";
57"P5E_CPU1_P0_TX_DP<4>";
58"P5E_CPU1_P0_TX_DP<1>";
59"P5E_CPU1_P0_TX_DP<0>";
60"P5E_CPU0_G3_TX_C_DP<9>";
61"P5E_CPU0_G3_TX_DP<7>";
62"P5E_CPU0_G3_TX_DN<4>";
63"P5E_CPU0_G3_TX_DP<4>";
64"P5E_CPU0_G3_TX_DP<3>";
65"P5E_CPU0_G3_TX_DN<2>";
66"P5E_CPU0_G3_TX_DN<1>";
67"P5E_CPU0_G3_TX_DP<1>";
68"P5E_CPU0_G3_TX_C_DN<6>";
69"P5E_CPU0_G3_TX_C_DN<7>";
70"P5E_CPU0_G3_TX_C_DN<8>";
71"P5E_CPU0_G3_TX_C_DP<15>";
72"P5E_CPU0_G3_TX_C_DN<15>";
73"P5E_CPU0_G3_TX_C_DP<0>";
74"P5E_CPU0_G3_TX_C_DN<0>";
75"P5E_CPU0_G3_TX_C_DP<2>";
76"P5E_CPU0_G3_TX_C_DN<2>";
77"P5E_CPU0_G3_TX_C_DP<3>";
78"P5E_CPU0_G3_TX_C_DN<3>";
79"P5E_CPU0_G3_TX_C_DP<4>";
80"P5E_CPU0_G3_TX_C_DN<4>";
81"P5E_CPU0_G3_TX_C_DN<5>";
82"P5E_CPU0_G3_TX_C_DP<10>";
83"P5E_CPU0_G3_TX_C_DN<10>";
84"P5E_CPU0_G3_TX_C_DN<11>";
85"P5E_CPU0_G3_TX_C_DN<12>";
86"P5E_CPU0_G3_TX_C_DP<13>";
87"P5E_CPU0_G3_TX_C_DN<13>";
88"P5E_CPU0_G3_TX_C_DN<9>";
89"P5E_CPU0_G3_TX_C_DP<14>";
90"P5E_CPU0_G3_TX_C_DN<14>";
91"P5E_CPU0_G3_TX_DN<11>";
92"P5E_CPU0_G3_TX_DP<14>";
93"P5E_CPU0_G3_TX_DP<15>";
94"P5E_CPU0_G3_TX_DP<11>";
95"P5E_CPU0_G3_TX_DP<12>";
96"P5E_CPU0_G3_TX_DN<8>";
97"P5E_CPU0_G3_TX_DN<12>";
98"P5E_CPU0_G3_TX_DN<9>";
99"P5E_CPU0_G3_TX_DN<10>";
100"P5E_CPU0_G3_TX_DN<14>";
101"P5E_CPU0_G3_TX_DN<13>";
102"P5E_CPU0_G3_TX_DN<15>";
103"P5E_CPU0_G3_TX_DP<6>";
104"P5E_CPU0_G3_TX_DN<7>";
105"P5E_CPU0_G3_TX_DP<5>";
106"P5E_CPU0_G3_TX_DN<5>";
107"P5E_CPU0_G3_TX_DN<3>";
108"P5E_CPU0_G3_TX_DN<0>";
109"P5E_CPU0_G3_TX_DP<0>";
110"P5E_CPU0_G3_TX_C_DN<1>";
111"P5E_CPU0_G3_TX_DP<2>";
112"P5E_CPU1_P0_TX_C_DN<3>";
113"P5E_CPU1_P0_TX_C_DP<3>";
114"P5E_CPU1_P0_TX_C_DN<2>";
115"P5E_CPU1_P0_TX_C_DP<2>";
116"P5E_CPU1_P0_TX_C_DN<1>";
117"P5E_CPU1_P0_TX_C_DN<0>";
118"P5E_CPU1_P0_TX_C_DP<0>";
119"P5E_CPU0_G3_TX_C_DP<8>";
120"P5E_CPU0_G3_TX_C_DP<1>";
121"P5E_CPU0_G3_TX_C_DP<5>";
122"P5E_CPU0_G3_TX_C_DP<6>";
123"P5E_CPU0_G3_TX_DP<9>";
124"P5E_CPU0_G3_TX_DP<10>";
125"P5E_CPU0_G3_TX_DP<13>";
126"P5E_CPU0_G3_TX_C_DP<11>";
127"P5E_CPU0_G3_TX_C_DP<12>";
128"P5E_CPU0_G3_TX_DP<8>";
129"P5E_CPU0_G3_TX_C_DP<7>";
130"P5E_CPU1_P0_TX_DP<2>";
131"P5E_CPU1_P0_TX_DN<2>";
132"P5E_CPU1_P0_TX_DN<3>";
133"P5E_CPU1_P0_TX_DP<5>";
134"P5E_CPU1_P0_TX_DP<6>";
135"P5E_CPU1_P0_TX_DP<9>";
136"P5E_CPU1_P0_TX_DP<11>";
137"P5E_CPU1_P0_TX_DP<13>";
138"P5E_CPU1_P0_TX_DP<8>";
139"P5E_CPU1_P0_TX_DN<8>";
140"P5E_CPU1_P0_TX_C_DN<9>";
141"P5E_CPU1_P0_TX_C_DP<10>";
142"P5E_CPU1_P0_TX_C_DN<10>";
143"P5E_CPU1_P0_TX_C_DP<11>";
144"P5E_CPU1_P0_TX_C_DN<8>";
%"TAP"
"1","(-1900,150)","2","standard","I213";
;
CDS_LIB"standard"
BODY_TYPE"PLUMBING"
HDL_TAP"TRUE";
"B \NAC \NWC"12;
"S \NAC"
BN"0"109;
%"TAP"
"1","(-1900,350)","2","standard","I214";
;
CDS_LIB"standard"
BODY_TYPE"PLUMBING"
HDL_TAP"TRUE";
"B \NAC \NWC"12;
"S \NAC"
BN"1"67;
%"TAP"
"1","(-1650,200)","2","standard","I215";
;
CDS_LIB"standard"
BODY_TYPE"PLUMBING"
HDL_TAP"TRUE";
"B \NAC \NWC"14;
"S \NAC"
BN"0"108;
%"TAP"
"1","(-1650,400)","2","standard","I216";
;
CDS_LIB"standard"
BODY_TYPE"PLUMBING"
HDL_TAP"TRUE";
"B \NAC \NWC"14;
"S \NAC"
BN"1"66;
%"TAP"
"1","(-1900,750)","2","standard","I217";
;
CDS_LIB"standard"
BODY_TYPE"PLUMBING"
HDL_TAP"TRUE";
"B \NAC \NWC"12;
"S \NAC"
BN"3"64;
%"TAP"
"1","(-1900,550)","2","standard","I218";
;
CDS_LIB"standard"
BODY_TYPE"PLUMBING"
HDL_TAP"TRUE";
"B \NAC \NWC"12;
"S \NAC"
BN"2"111;
%"TAP"
"1","(-1900,950)","2","standard","I219";
;
CDS_LIB"standard"
BODY_TYPE"PLUMBING"
HDL_TAP"TRUE";
"B \NAC \NWC"12;
"S \NAC"
BN"4"63;
%"TAP"
"1","(-1650,600)","2","standard","I220";
;
CDS_LIB"standard"
BODY_TYPE"PLUMBING"
HDL_TAP"TRUE";
"B \NAC \NWC"14;
"S \NAC"
BN"2"65;
%"TAP"
"1","(-1650,800)","2","standard","I221";
;
CDS_LIB"standard"
BODY_TYPE"PLUMBING"
HDL_TAP"TRUE";
"B \NAC \NWC"14;
"S \NAC"
BN"3"107;
%"TAP"
"1","(-1650,1000)","2","standard","I222";
;
CDS_LIB"standard"
BODY_TYPE"PLUMBING"
HDL_TAP"TRUE";
"B \NAC \NWC"14;
"S \NAC"
BN"4"62;
%"TAP"
"1","(-1900,1150)","2","standard","I223";
;
CDS_LIB"standard"
BODY_TYPE"PLUMBING"
HDL_TAP"TRUE";
"B \NAC \NWC"12;
"S \NAC"
BN"5"105;
%"TAP"
"1","(-1900,1350)","2","standard","I224";
;
CDS_LIB"standard"
BODY_TYPE"PLUMBING"
HDL_TAP"TRUE";
"B \NAC \NWC"12;
"S \NAC"
BN"6"103;
%"TAP"
"1","(-1650,1200)","2","standard","I225";
;
CDS_LIB"standard"
BODY_TYPE"PLUMBING"
HDL_TAP"TRUE";
"B \NAC \NWC"14;
"S \NAC"
BN"5"106;
%"TAP"
"1","(-1650,1400)","2","standard","I226";
;
CDS_LIB"standard"
BODY_TYPE"PLUMBING"
HDL_TAP"TRUE";
"B \NAC \NWC"14;
"S \NAC"
BN"6"17;
%"TAP"
"1","(-1900,1550)","2","standard","I227";
;
CDS_LIB"standard"
BODY_TYPE"PLUMBING"
HDL_TAP"TRUE";
"B \NAC \NWC"12;
"S \NAC"
BN"7"61;
%"TAP"
"1","(-1650,1600)","2","standard","I228";
;
CDS_LIB"standard"
BODY_TYPE"PLUMBING"
HDL_TAP"TRUE";
"B \NAC \NWC"14;
"S \NAC"
BN"7"104;
%"Q_CAP_DIFFBUS"
"2","(-925,150)","2","pure_quanta","I229";
;
LOCATION"C1579"
$SEC"1"
CDS_SEC"1"
VALUE"DIFF BUS_0.22UF"
PIN_NAMES_ROTATE"TRUE"
CDS_LIB"pure_quanta"
CDS_LMAN_SYM_OUTLINE"-25,50,25,-50"
VOLTAGE"6.3V"
MATERIAL"X6S"
PACK_TYPE"C0201"
TOLERANCE"20%"
PART_NUMBER"SP_CH4221MEE01";
"2"
$PN"2"109;
"1"
$PN"1"73;
%"Q_CAP_DIFFBUS"
"2","(-925,200)","2","pure_quanta","I230";
;
LOCATION"C1578"
$SEC"1"
CDS_SEC"1"
VALUE"DIFF BUS_0.22UF"
PIN_NAMES_ROTATE"TRUE"
CDS_LIB"pure_quanta"
CDS_LMAN_SYM_OUTLINE"-25,50,25,-50"
VOLTAGE"6.3V"
MATERIAL"X6S"
PACK_TYPE"C0201"
TOLERANCE"20%"
PART_NUMBER"SP_CH4221MEE01";
"2"
$PN"2"108;
"1"
$PN"1"74;
%"Q_CAP_DIFFBUS"
"2","(-925,550)","2","pure_quanta","I231";
;
LOCATION"C1575"
$SEC"1"
CDS_SEC"1"
VALUE"DIFF BUS_0.22UF"
PIN_NAMES_ROTATE"TRUE"
CDS_LIB"pure_quanta"
CDS_LMAN_SYM_OUTLINE"-25,50,25,-50"
VOLTAGE"6.3V"
MATERIAL"X6S"
PACK_TYPE"C0201"
TOLERANCE"20%"
PART_NUMBER"SP_CH4221MEE01";
"2"
$PN"2"111;
"1"
$PN"1"75;
%"Q_CAP_DIFFBUS"
"2","(-925,600)","2","pure_quanta","I232";
;
LOCATION"C1574"
$SEC"1"
CDS_SEC"1"
VALUE"DIFF BUS_0.22UF"
PIN_NAMES_ROTATE"TRUE"
CDS_LIB"pure_quanta"
CDS_LMAN_SYM_OUTLINE"-25,50,25,-50"
VOLTAGE"6.3V"
MATERIAL"X6S"
PACK_TYPE"C0201"
TOLERANCE"20%"
PART_NUMBER"SP_CH4221MEE01";
"2"
$PN"2"65;
"1"
$PN"1"76;
%"Q_CAP_DIFFBUS"
"2","(-925,750)","2","pure_quanta","I233";
;
LOCATION"C1573"
$SEC"1"
CDS_SEC"1"
VALUE"DIFF BUS_0.22UF"
PIN_NAMES_ROTATE"TRUE"
CDS_LMAN_SYM_OUTLINE"-25,50,25,-50"
CDS_LIB"pure_quanta"
VOLTAGE"6.3V"
MATERIAL"X6S"
PACK_TYPE"C0201"
TOLERANCE"20%"
PART_NUMBER"SP_CH4221MEE01";
"2"
$PN"2"64;
"1"
$PN"1"77;
%"Q_CAP_DIFFBUS"
"2","(-925,800)","2","pure_quanta","I234";
;
LOCATION"C1572"
$SEC"1"
CDS_SEC"1"
VALUE"DIFF BUS_0.22UF"
PIN_NAMES_ROTATE"TRUE"
CDS_LMAN_SYM_OUTLINE"-25,50,25,-50"
CDS_LIB"pure_quanta"
VOLTAGE"6.3V"
MATERIAL"X6S"
PACK_TYPE"C0201"
TOLERANCE"20%"
PART_NUMBER"SP_CH4221MEE01";
"2"
$PN"2"107;
"1"
$PN"1"78;
%"Q_CAP_DIFFBUS"
"2","(-925,1000)","2","pure_quanta","I235";
;
LOCATION"C1570"
$SEC"1"
CDS_SEC"1"
VALUE"DIFF BUS_0.22UF"
PIN_NAMES_ROTATE"TRUE"
CDS_LIB"pure_quanta"
CDS_LMAN_SYM_OUTLINE"-25,50,25,-50"
VOLTAGE"6.3V"
MATERIAL"X6S"
PACK_TYPE"C0201"
TOLERANCE"20%"
PART_NUMBER"SP_CH4221MEE01";
"2"
$PN"2"62;
"1"
$PN"1"80;
%"Q_CAP_DIFFBUS"
"2","(-925,950)","2","pure_quanta","I236";
;
LOCATION"C1571"
$SEC"1"
CDS_SEC"1"
VALUE"DIFF BUS_0.22UF"
PIN_NAMES_ROTATE"TRUE"
CDS_LIB"pure_quanta"
CDS_LMAN_SYM_OUTLINE"-25,50,25,-50"
VOLTAGE"6.3V"
MATERIAL"X6S"
PACK_TYPE"C0201"
TOLERANCE"20%"
PART_NUMBER"SP_CH4221MEE01";
"2"
$PN"2"63;
"1"
$PN"1"79;
%"Q_CAP_DIFFBUS"
"2","(-925,1150)","2","pure_quanta","I237";
;
LOCATION"C1569"
$SEC"1"
CDS_SEC"1"
VALUE"DIFF BUS_0.22UF"
PIN_NAMES_ROTATE"TRUE"
CDS_LIB"pure_quanta"
CDS_LMAN_SYM_OUTLINE"-25,50,25,-50"
VOLTAGE"6.3V"
MATERIAL"X6S"
PACK_TYPE"C0201"
TOLERANCE"20%"
PART_NUMBER"SP_CH4221MEE01";
"2"
$PN"2"105;
"1"
$PN"1"121;
%"Q_CAP_DIFFBUS"
"2","(-925,1200)","2","pure_quanta","I238";
;
LOCATION"C1568"
$SEC"1"
CDS_SEC"1"
VALUE"DIFF BUS_0.22UF"
PIN_NAMES_ROTATE"TRUE"
CDS_LIB"pure_quanta"
CDS_LMAN_SYM_OUTLINE"-25,50,25,-50"
VOLTAGE"6.3V"
MATERIAL"X6S"
PACK_TYPE"C0201"
TOLERANCE"20%"
PART_NUMBER"SP_CH4221MEE01";
"2"
$PN"2"106;
"1"
$PN"1"81;
%"Q_CAP_DIFFBUS"
"2","(-925,1350)","2","pure_quanta","I239";
;
LOCATION"C47"
$SEC"1"
CDS_SEC"1"
VALUE"DIFF BUS_0.22UF"
PIN_NAMES_ROTATE"TRUE"
CDS_LIB"pure_quanta"
CDS_LMAN_SYM_OUTLINE"-25,50,25,-50"
VOLTAGE"6.3V"
MATERIAL"X6S"
PACK_TYPE"C0201"
TOLERANCE"20%"
PART_NUMBER"SP_CH4221MEE01";
"2"
$PN"2"103;
"1"
$PN"1"122;
%"Q_CAP_DIFFBUS"
"2","(-925,1400)","2","pure_quanta","I240";
;
LOCATION"C1566"
$SEC"1"
CDS_SEC"1"
VALUE"DIFF BUS_0.22UF"
PIN_NAMES_ROTATE"TRUE"
CDS_LIB"pure_quanta"
CDS_LMAN_SYM_OUTLINE"-25,50,25,-50"
VOLTAGE"6.3V"
MATERIAL"X6S"
PACK_TYPE"C0201"
TOLERANCE"20%"
PART_NUMBER"SP_CH4221MEE01";
"2"
$PN"2"17;
"1"
$PN"1"68;
%"Q_CAP_DIFFBUS"
"2","(-925,1550)","2","pure_quanta","I241";
;
LOCATION"C1565"
$SEC"1"
CDS_SEC"1"
VALUE"DIFF BUS_0.22UF"
PIN_NAMES_ROTATE"TRUE"
CDS_LIB"pure_quanta"
CDS_LMAN_SYM_OUTLINE"-25,50,25,-50"
VOLTAGE"6.3V"
MATERIAL"X6S"
PACK_TYPE"C0201"
TOLERANCE"20%"
PART_NUMBER"SP_CH4221MEE01";
"2"
$PN"2"61;
"1"
$PN"1"129;
%"Q_CAP_DIFFBUS"
"2","(-925,1600)","2","pure_quanta","I242";
;
LOCATION"C46"
$SEC"1"
CDS_SEC"1"
VALUE"DIFF BUS_0.22UF"
PIN_NAMES_ROTATE"TRUE"
CDS_LMAN_SYM_OUTLINE"-25,50,25,-50"
CDS_LIB"pure_quanta"
VOLTAGE"6.3V"
MATERIAL"X6S"
PACK_TYPE"C0201"
TOLERANCE"20%"
PART_NUMBER"SP_CH4221MEE01";
"2"
$PN"2"104;
"1"
$PN"1"69;
%"TAP"
"1","(-1900,2125)","2","standard","I243";
;
CDS_LIB"standard"
BODY_TYPE"PLUMBING"
HDL_TAP"TRUE";
"B \NAC \NWC"8;
"S \NAC"
BN"8"128;
%"TAP"
"1","(-1900,2325)","2","standard","I244";
;
CDS_LIB"standard"
BODY_TYPE"PLUMBING"
HDL_TAP"TRUE";
"B \NAC \NWC"8;
"S \NAC"
BN"9"123;
%"TAP"
"1","(-1900,2525)","2","standard","I245";
;
CDS_LIB"standard"
BODY_TYPE"PLUMBING"
HDL_TAP"TRUE";
"B \NAC \NWC"8;
"S \NAC"
BN"10"124;
%"TAP"
"1","(-1650,2175)","2","standard","I246";
;
CDS_LIB"standard"
BODY_TYPE"PLUMBING"
HDL_TAP"TRUE";
"B \NAC \NWC"15;
"S \NAC"
BN"8"96;
%"TAP"
"1","(-1650,2375)","2","standard","I247";
;
CDS_LIB"standard"
BODY_TYPE"PLUMBING"
HDL_TAP"TRUE";
"B \NAC \NWC"15;
"S \NAC"
BN"9"98;
%"TAP"
"1","(-1900,2725)","2","standard","I248";
;
CDS_LIB"standard"
BODY_TYPE"PLUMBING"
HDL_TAP"TRUE";
"B \NAC \NWC"8;
"S \NAC"
BN"11"94;
%"TAP"
"1","(-1900,2925)","2","standard","I249";
;
CDS_LIB"standard"
BODY_TYPE"PLUMBING"
HDL_TAP"TRUE";
"B \NAC \NWC"8;
"S \NAC"
BN"12"95;
%"TAP"
"1","(-1650,2775)","2","standard","I250";
;
CDS_LIB"standard"
BODY_TYPE"PLUMBING"
HDL_TAP"TRUE";
"B \NAC \NWC"15;
"S \NAC"
BN"11"91;
%"TAP"
"1","(-1650,2575)","2","standard","I251";
;
CDS_LIB"standard"
BODY_TYPE"PLUMBING"
HDL_TAP"TRUE";
"B \NAC \NWC"15;
"S \NAC"
BN"10"99;
%"TAP"
"1","(-1650,2975)","2","standard","I252";
;
CDS_LIB"standard"
BODY_TYPE"PLUMBING"
HDL_TAP"TRUE";
"B \NAC \NWC"15;
"S \NAC"
BN"12"97;
%"TAP"
"1","(-1900,3325)","2","standard","I253";
;
CDS_LIB"standard"
BODY_TYPE"PLUMBING"
HDL_TAP"TRUE";
"B \NAC \NWC"8;
"S \NAC"
BN"14"92;
%"TAP"
"1","(-1900,3125)","2","standard","I254";
;
CDS_LIB"standard"
BODY_TYPE"PLUMBING"
HDL_TAP"TRUE";
"B \NAC \NWC"8;
"S \NAC"
BN"13"125;
%"TAP"
"1","(-1900,3525)","2","standard","I255";
;
CDS_LIB"standard"
BODY_TYPE"PLUMBING"
HDL_TAP"TRUE";
"B \NAC \NWC"8;
"S \NAC"
BN"15"93;
%"TAP"
"1","(-1650,3175)","2","standard","I256";
;
CDS_LIB"standard"
BODY_TYPE"PLUMBING"
HDL_TAP"TRUE";
"B \NAC \NWC"15;
"S \NAC"
BN"13"101;
%"TAP"
"1","(-1650,3575)","2","standard","I257";
;
CDS_LIB"standard"
BODY_TYPE"PLUMBING"
HDL_TAP"TRUE";
"B \NAC \NWC"15;
"S \NAC"
BN"15"102;
%"TAP"
"1","(-1650,3375)","2","standard","I258";
;
CDS_LIB"standard"
BODY_TYPE"PLUMBING"
HDL_TAP"TRUE";
"B \NAC \NWC"15;
"S \NAC"
BN"14"100;
%"Q_CAP_DIFFBUS"
"2","(-925,2125)","2","pure_quanta","I259";
;
LOCATION"C44"
$SEC"1"
CDS_SEC"1"
VALUE"DIFF BUS_0.22UF"
CDS_LMAN_SYM_OUTLINE"-25,50,25,-50"
CDS_LIB"pure_quanta"
PIN_NAMES_ROTATE"TRUE"
VOLTAGE"6.3V"
MATERIAL"X6S"
PACK_TYPE"C0201"
TOLERANCE"20%"
PART_NUMBER"SP_CH4221MEE01";
"2"
$PN"2"128;
"1"
$PN"1"119;
%"Q_CAP_DIFFBUS"
"2","(-925,2175)","2","pure_quanta","I260";
;
LOCATION"C1794"
$SEC"1"
CDS_SEC"1"
VALUE"DIFF BUS_0.22UF"
CDS_LMAN_SYM_OUTLINE"-25,50,25,-50"
CDS_LIB"pure_quanta"
PIN_NAMES_ROTATE"TRUE"
VOLTAGE"6.3V"
MATERIAL"X6S"
PACK_TYPE"C0201"
TOLERANCE"20%"
PART_NUMBER"SP_CH4221MEE01";
"2"
$PN"2"96;
"1"
$PN"1"70;
%"Q_CAP_DIFFBUS"
"2","(-925,2325)","2","pure_quanta","I261";
;
LOCATION"C1793"
$SEC"1"
CDS_SEC"1"
VALUE"DIFF BUS_0.22UF"
CDS_LMAN_SYM_OUTLINE"-25,50,25,-50"
CDS_LIB"pure_quanta"
PIN_NAMES_ROTATE"TRUE"
VOLTAGE"6.3V"
MATERIAL"X6S"
PACK_TYPE"C0201"
TOLERANCE"20%"
PART_NUMBER"SP_CH4221MEE01";
"2"
$PN"2"123;
"1"
$PN"1"60;
%"Q_CAP_DIFFBUS"
"2","(-925,2375)","2","pure_quanta","I262";
;
LOCATION"C1560"
$SEC"1"
CDS_SEC"1"
VALUE"DIFF BUS_0.22UF"
CDS_LIB"pure_quanta"
CDS_LMAN_SYM_OUTLINE"-25,50,25,-50"
PIN_NAMES_ROTATE"TRUE"
VOLTAGE"6.3V"
MATERIAL"X6S"
PACK_TYPE"C0201"
TOLERANCE"20%"
PART_NUMBER"SP_CH4221MEE01";
"2"
$PN"2"98;
"1"
$PN"1"88;
%"Q_CAP_DIFFBUS"
"2","(-925,2525)","2","pure_quanta","I263";
;
LOCATION"C1559"
$SEC"1"
CDS_SEC"1"
VALUE"DIFF BUS_0.22UF"
CDS_LMAN_SYM_OUTLINE"-25,50,25,-50"
CDS_LIB"pure_quanta"
PIN_NAMES_ROTATE"TRUE"
VOLTAGE"6.3V"
MATERIAL"X6S"
PACK_TYPE"C0201"
TOLERANCE"20%"
PART_NUMBER"SP_CH4221MEE01";
"2"
$PN"2"124;
"1"
$PN"1"82;
%"Q_CAP_DIFFBUS"
"2","(-925,2575)","2","pure_quanta","I264";
;
LOCATION"C1558"
$SEC"1"
CDS_SEC"1"
VALUE"DIFF BUS_0.22UF"
CDS_LMAN_SYM_OUTLINE"-25,50,25,-50"
CDS_LIB"pure_quanta"
PIN_NAMES_ROTATE"TRUE"
VOLTAGE"6.3V"
MATERIAL"X6S"
PACK_TYPE"C0201"
TOLERANCE"20%"
PART_NUMBER"SP_CH4221MEE01";
"2"
$PN"2"99;
"1"
$PN"1"83;
%"Q_CAP_DIFFBUS"
"2","(-925,2775)","2","pure_quanta","I265";
;
LOCATION"C1556"
$SEC"1"
CDS_SEC"1"
VALUE"DIFF BUS_0.22UF"
CDS_LIB"pure_quanta"
CDS_LMAN_SYM_OUTLINE"-25,50,25,-50"
PIN_NAMES_ROTATE"TRUE"
VOLTAGE"6.3V"
MATERIAL"X6S"
PACK_TYPE"C0201"
TOLERANCE"20%"
PART_NUMBER"SP_CH4221MEE01";
"2"
$PN"2"91;
"1"
$PN"1"84;
%"Q_CAP_DIFFBUS"
"2","(-925,2725)","2","pure_quanta","I266";
;
LOCATION"C1557"
$SEC"1"
CDS_SEC"1"
VALUE"DIFF BUS_0.22UF"
CDS_LIB"pure_quanta"
CDS_LMAN_SYM_OUTLINE"-25,50,25,-50"
PIN_NAMES_ROTATE"TRUE"
VOLTAGE"6.3V"
MATERIAL"X6S"
PACK_TYPE"C0201"
TOLERANCE"20%"
PART_NUMBER"SP_CH4221MEE01";
"2"
$PN"2"94;
"1"
$PN"1"126;
%"Q_CAP_DIFFBUS"
"2","(-925,2925)","2","pure_quanta","I267";
;
LOCATION"C1555"
$SEC"1"
CDS_SEC"1"
VALUE"DIFF BUS_0.22UF"
CDS_LMAN_SYM_OUTLINE"-25,50,25,-50"
CDS_LIB"pure_quanta"
PIN_NAMES_ROTATE"TRUE"
VOLTAGE"6.3V"
MATERIAL"X6S"
PACK_TYPE"C0201"
TOLERANCE"20%"
PART_NUMBER"SP_CH4221MEE01";
"2"
$PN"2"95;
"1"
$PN"1"127;
%"Q_CAP_DIFFBUS"
"2","(-925,2975)","2","pure_quanta","I268";
;
LOCATION"C41"
$SEC"1"
CDS_SEC"1"
VALUE"DIFF BUS_0.22UF"
CDS_LMAN_SYM_OUTLINE"-25,50,25,-50"
CDS_LIB"pure_quanta"
PIN_NAMES_ROTATE"TRUE"
VOLTAGE"6.3V"
MATERIAL"X6S"
PACK_TYPE"C0201"
TOLERANCE"20%"
PART_NUMBER"SP_CH4221MEE01";
"2"
$PN"2"97;
"1"
$PN"1"85;
%"Q_CAP_DIFFBUS"
"2","(-925,3125)","2","pure_quanta","I269";
;
LOCATION"C1553"
$SEC"1"
CDS_SEC"1"
VALUE"DIFF BUS_0.22UF"
CDS_LMAN_SYM_OUTLINE"-25,50,25,-50"
CDS_LIB"pure_quanta"
PIN_NAMES_ROTATE"TRUE"
VOLTAGE"6.3V"
MATERIAL"X6S"
PACK_TYPE"C0201"
TOLERANCE"20%"
PART_NUMBER"SP_CH4221MEE01";
"2"
$PN"2"125;
"1"
$PN"1"86;
%"Q_CAP_DIFFBUS"
"2","(-925,3175)","2","pure_quanta","I270";
;
LOCATION"C1552"
$SEC"1"
CDS_SEC"1"
VALUE"DIFF BUS_0.22UF"
CDS_LMAN_SYM_OUTLINE"-25,50,25,-50"
CDS_LIB"pure_quanta"
PIN_NAMES_ROTATE"TRUE"
VOLTAGE"6.3V"
MATERIAL"X6S"
PACK_TYPE"C0201"
TOLERANCE"20%"
PART_NUMBER"SP_CH4221MEE01";
"2"
$PN"2"101;
"1"
$PN"1"87;
%"Q_CAP_DIFFBUS"
"2","(-925,3325)","2","pure_quanta","I271";
;
LOCATION"C1792"
$SEC"1"
CDS_SEC"1"
VALUE"DIFF BUS_0.22UF"
CDS_LMAN_SYM_OUTLINE"-25,50,25,-50"
CDS_LIB"pure_quanta"
PIN_NAMES_ROTATE"TRUE"
VOLTAGE"6.3V"
MATERIAL"X6S"
PACK_TYPE"C0201"
TOLERANCE"20%"
PART_NUMBER"SP_CH4221MEE01";
"2"
$PN"2"92;
"1"
$PN"1"89;
%"Q_CAP_DIFFBUS"
"2","(-925,3375)","2","pure_quanta","I272";
;
LOCATION"C1550"
$SEC"1"
CDS_SEC"1"
VALUE"DIFF BUS_0.22UF"
CDS_LMAN_SYM_OUTLINE"-25,50,25,-50"
CDS_LIB"pure_quanta"
PIN_NAMES_ROTATE"TRUE"
VOLTAGE"6.3V"
MATERIAL"X6S"
PACK_TYPE"C0201"
TOLERANCE"20%"
PART_NUMBER"SP_CH4221MEE01";
"2"
$PN"2"100;
"1"
$PN"1"90;
%"Q_CAP_DIFFBUS"
"2","(-925,3575)","2","pure_quanta","I273";
;
LOCATION"C1548"
$SEC"1"
CDS_SEC"1"
PACK_TYPE"C0201"
VALUE"DIFF BUS_0.22UF"
VOLTAGE"6.3V"
MATERIAL"X6S"
TOLERANCE"20%"
CDS_LIB"pure_quanta"
CDS_LMAN_SYM_OUTLINE"-25,50,25,-50"
PIN_NAMES_ROTATE"TRUE"
PART_NUMBER"SP_CH4221MEE01";
"2"
$PN"2"102;
"1"
$PN"1"72;
%"Q_CAP_DIFFBUS"
"2","(-925,3525)","2","pure_quanta","I274";
;
LOCATION"C1549"
$SEC"1"
CDS_SEC"1"
VALUE"DIFF BUS_0.22UF"
CDS_LMAN_SYM_OUTLINE"-25,50,25,-50"
CDS_LIB"pure_quanta"
PIN_NAMES_ROTATE"TRUE"
VOLTAGE"6.3V"
MATERIAL"X6S"
PACK_TYPE"C0201"
TOLERANCE"20%"
PART_NUMBER"SP_CH4221MEE01";
"2"
$PN"2"93;
"1"
$PN"1"71;
%"TAP"
"1","(-375,200)","0","standard","I275";
;
CDS_LIB"standard"
BODY_TYPE"PLUMBING"
HDL_TAP"TRUE";
"B \NAC \NWC"13;
"S \NAC"
BN"0"74;
%"TAP"
"1","(-175,150)","0","standard","I276";
;
CDS_LIB"standard"
BODY_TYPE"PLUMBING"
HDL_TAP"TRUE";
"B \NAC \NWC"7;
"S \NAC"
BN"0"73;
%"TAP"
"1","(-175,350)","0","standard","I277";
;
CDS_LIB"standard"
BODY_TYPE"PLUMBING"
HDL_TAP"TRUE";
"B \NAC \NWC"7;
"S \NAC"
BN"1"120;
%"TAP"
"1","(-375,400)","0","standard","I278";
;
CDS_LIB"standard"
BODY_TYPE"PLUMBING"
HDL_TAP"TRUE";
"B \NAC \NWC"13;
"S \NAC"
BN"1"110;
%"TAP"
"1","(-375,600)","0","standard","I279";
;
CDS_LIB"standard"
BODY_TYPE"PLUMBING"
HDL_TAP"TRUE";
"B \NAC \NWC"13;
"S \NAC"
BN"2"76;
%"TAP"
"1","(-175,550)","0","standard","I280";
;
CDS_LIB"standard"
BODY_TYPE"PLUMBING"
HDL_TAP"TRUE";
"B \NAC \NWC"7;
"S \NAC"
BN"2"75;
%"TAP"
"1","(-175,750)","0","standard","I281";
;
CDS_LIB"standard"
BODY_TYPE"PLUMBING"
HDL_TAP"TRUE";
"B \NAC \NWC"7;
"S \NAC"
BN"3"77;
%"TAP"
"1","(-375,1000)","0","standard","I282";
;
CDS_LIB"standard"
BODY_TYPE"PLUMBING"
HDL_TAP"TRUE";
"B \NAC \NWC"13;
"S \NAC"
BN"4"80;
%"TAP"
"1","(-375,800)","0","standard","I283";
;
CDS_LIB"standard"
BODY_TYPE"PLUMBING"
HDL_TAP"TRUE";
"B \NAC \NWC"13;
"S \NAC"
BN"3"78;
%"TAP"
"1","(-175,950)","0","standard","I284";
;
CDS_LIB"standard"
BODY_TYPE"PLUMBING"
HDL_TAP"TRUE";
"B \NAC \NWC"7;
"S \NAC"
BN"4"79;
%"TAP"
"1","(-375,1200)","0","standard","I285";
;
CDS_LIB"standard"
BODY_TYPE"PLUMBING"
HDL_TAP"TRUE";
"B \NAC \NWC"13;
"S \NAC"
BN"5"81;
%"TAP"
"1","(-175,1150)","0","standard","I286";
;
CDS_LIB"standard"
BODY_TYPE"PLUMBING"
HDL_TAP"TRUE";
"B \NAC \NWC"7;
"S \NAC"
BN"5"121;
%"TAP"
"1","(-375,1400)","0","standard","I287";
;
CDS_LIB"standard"
BODY_TYPE"PLUMBING"
HDL_TAP"TRUE";
"B \NAC \NWC"13;
"S \NAC"
BN"6"68;
%"TAP"
"1","(-175,1350)","0","standard","I288";
;
CDS_LIB"standard"
BODY_TYPE"PLUMBING"
HDL_TAP"TRUE";
"B \NAC \NWC"7;
"S \NAC"
BN"6"122;
%"TAP"
"1","(-375,1600)","0","standard","I289";
;
CDS_LIB"standard"
BODY_TYPE"PLUMBING"
HDL_TAP"TRUE";
"B \NAC \NWC"13;
"S \NAC"
BN"7"69;
%"TAP"
"1","(-175,1550)","0","standard","I290";
;
CDS_LIB"standard"
BODY_TYPE"PLUMBING"
HDL_TAP"TRUE";
"B \NAC \NWC"7;
"S \NAC"
BN"7"129;
%"TAP"
"1","(-375,2175)","0","standard","I293";
;
CDS_LIB"standard"
BODY_TYPE"PLUMBING"
HDL_TAP"TRUE";
"B \NAC \NWC"16;
"S \NAC"
BN"8"70;
%"TAP"
"1","(-175,2125)","0","standard","I294";
;
CDS_LIB"standard"
BODY_TYPE"PLUMBING"
HDL_TAP"TRUE";
"B \NAC \NWC"9;
"S \NAC"
BN"8"119;
%"TAP"
"1","(-375,2375)","0","standard","I295";
;
CDS_LIB"standard"
BODY_TYPE"PLUMBING"
HDL_TAP"TRUE";
"B \NAC \NWC"16;
"S \NAC"
BN"9"88;
%"TAP"
"1","(-175,2325)","0","standard","I296";
;
CDS_LIB"standard"
BODY_TYPE"PLUMBING"
HDL_TAP"TRUE";
"B \NAC \NWC"9;
"S \NAC"
BN"9"60;
%"TAP"
"1","(-175,2525)","0","standard","I297";
;
CDS_LIB"standard"
BODY_TYPE"PLUMBING"
HDL_TAP"TRUE";
"B \NAC \NWC"9;
"S \NAC"
BN"10"82;
%"TAP"
"1","(-375,2775)","0","standard","I298";
;
CDS_LIB"standard"
BODY_TYPE"PLUMBING"
HDL_TAP"TRUE";
"B \NAC \NWC"16;
"S \NAC"
BN"11"84;
%"TAP"
"1","(-375,2575)","0","standard","I299";
;
CDS_LIB"standard"
BODY_TYPE"PLUMBING"
HDL_TAP"TRUE";
"B \NAC \NWC"16;
"S \NAC"
BN"10"83;
%"TAP"
"1","(-175,2725)","0","standard","I300";
;
CDS_LIB"standard"
BODY_TYPE"PLUMBING"
HDL_TAP"TRUE";
"B \NAC \NWC"9;
"S \NAC"
BN"11"126;
%"TAP"
"1","(-375,2975)","0","standard","I301";
;
CDS_LIB"standard"
BODY_TYPE"PLUMBING"
HDL_TAP"TRUE";
"B \NAC \NWC"16;
"S \NAC"
BN"12"85;
%"TAP"
"1","(-175,2925)","0","standard","I302";
;
CDS_LIB"standard"
BODY_TYPE"PLUMBING"
HDL_TAP"TRUE";
"B \NAC \NWC"9;
"S \NAC"
BN"12"127;
%"TAP"
"1","(-375,3175)","0","standard","I303";
;
CDS_LIB"standard"
BODY_TYPE"PLUMBING"
HDL_TAP"TRUE";
"B \NAC \NWC"16;
"S \NAC"
BN"13"87;
%"TAP"
"1","(-175,3325)","0","standard","I304";
;
CDS_LIB"standard"
BODY_TYPE"PLUMBING"
HDL_TAP"TRUE";
"B \NAC \NWC"9;
"S \NAC"
BN"14"89;
%"TAP"
"1","(-175,3125)","0","standard","I305";
;
CDS_LIB"standard"
BODY_TYPE"PLUMBING"
HDL_TAP"TRUE";
"B \NAC \NWC"9;
"S \NAC"
BN"13"86;
%"TAP"
"1","(-375,3375)","0","standard","I306";
;
CDS_LIB"standard"
BODY_TYPE"PLUMBING"
HDL_TAP"TRUE";
"B \NAC \NWC"16;
"S \NAC"
BN"14"90;
%"TAP"
"1","(-375,3575)","0","standard","I307";
;
CDS_LIB"standard"
BODY_TYPE"PLUMBING"
HDL_TAP"TRUE";
"B \NAC \NWC"16;
"S \NAC"
BN"15"72;
%"TAP"
"1","(-175,3525)","0","standard","I308";
;
CDS_LIB"standard"
BODY_TYPE"PLUMBING"
HDL_TAP"TRUE";
"B \NAC \NWC"9;
"S \NAC"
BN"15"71;
%"Q_CAP_DIFFBUS"
"2","(-925,350)","2","pure_quanta","I311";
;
LOCATION"C1577"
$SEC"1"
CDS_SEC"1"
VALUE"DIFF BUS_0.22UF"
PIN_NAMES_ROTATE"TRUE"
CDS_LIB"pure_quanta"
CDS_LMAN_SYM_OUTLINE"-25,50,25,-50"
VOLTAGE"6.3V"
MATERIAL"X6S"
PACK_TYPE"C0201"
TOLERANCE"20%"
PART_NUMBER"SP_CH4221MEE01";
"2"
$PN"2"67;
"1"
$PN"1"120;
%"Q_CAP_DIFFBUS"
"2","(-925,400)","2","pure_quanta","I312";
;
LOCATION"C1576"
$SEC"1"
CDS_SEC"1"
VALUE"DIFF BUS_0.22UF"
PIN_NAMES_ROTATE"TRUE"
CDS_LMAN_SYM_OUTLINE"-25,50,25,-50"
CDS_LIB"pure_quanta"
VOLTAGE"6.3V"
MATERIAL"X6S"
PACK_TYPE"C0201"
TOLERANCE"20%"
PART_NUMBER"SP_CH4221MEE01";
"2"
$PN"2"66;
"1"
$PN"1"110;
%"TAP"
"1","(2600,150)","2","standard","I317";
;
CDS_LIB"standard"
BODY_TYPE"PLUMBING"
HDL_TAP"TRUE";
"B \NAC \NWC"5;
"S \NAC"
BN"0"59;
%"TAP"
"1","(2600,350)","2","standard","I318";
;
CDS_LIB"standard"
BODY_TYPE"PLUMBING"
HDL_TAP"TRUE";
"B \NAC \NWC"5;
"S \NAC"
BN"1"58;
%"TAP"
"1","(2850,200)","2","standard","I319";
;
CDS_LIB"standard"
BODY_TYPE"PLUMBING"
HDL_TAP"TRUE";
"B \NAC \NWC"6;
"S \NAC"
BN"0"55;
%"TAP"
"1","(2850,400)","2","standard","I320";
;
CDS_LIB"standard"
BODY_TYPE"PLUMBING"
HDL_TAP"TRUE";
"B \NAC \NWC"6;
"S \NAC"
BN"1"54;
%"TAP"
"1","(2600,550)","2","standard","I321";
;
CDS_LIB"standard"
BODY_TYPE"PLUMBING"
HDL_TAP"TRUE";
"B \NAC \NWC"5;
"S \NAC"
BN"2"130;
%"TAP"
"1","(2600,750)","2","standard","I322";
;
CDS_LIB"standard"
BODY_TYPE"PLUMBING"
HDL_TAP"TRUE";
"B \NAC \NWC"5;
"S \NAC"
BN"3"56;
%"TAP"
"1","(2600,950)","2","standard","I323";
;
CDS_LIB"standard"
BODY_TYPE"PLUMBING"
HDL_TAP"TRUE";
"B \NAC \NWC"5;
"S \NAC"
BN"4"57;
%"TAP"
"1","(2850,600)","2","standard","I324";
;
CDS_LIB"standard"
BODY_TYPE"PLUMBING"
HDL_TAP"TRUE";
"B \NAC \NWC"6;
"S \NAC"
BN"2"131;
%"TAP"
"1","(2850,800)","2","standard","I325";
;
CDS_LIB"standard"
BODY_TYPE"PLUMBING"
HDL_TAP"TRUE";
"B \NAC \NWC"6;
"S \NAC"
BN"3"132;
%"TAP"
"1","(2850,1000)","2","standard","I326";
;
CDS_LIB"standard"
BODY_TYPE"PLUMBING"
HDL_TAP"TRUE";
"B \NAC \NWC"6;
"S \NAC"
BN"4"53;
%"TAP"
"1","(2600,1150)","2","standard","I327";
;
CDS_LIB"standard"
BODY_TYPE"PLUMBING"
HDL_TAP"TRUE";
"B \NAC \NWC"5;
"S \NAC"
BN"5"133;
%"TAP"
"1","(2600,1350)","2","standard","I328";
;
CDS_LIB"standard"
BODY_TYPE"PLUMBING"
HDL_TAP"TRUE";
"B \NAC \NWC"5;
"S \NAC"
BN"6"134;
%"TAP"
"1","(2850,1200)","2","standard","I329";
;
CDS_LIB"standard"
BODY_TYPE"PLUMBING"
HDL_TAP"TRUE";
"B \NAC \NWC"6;
"S \NAC"
BN"5"52;
%"TAP"
"1","(2850,1400)","2","standard","I330";
;
CDS_LIB"standard"
BODY_TYPE"PLUMBING"
HDL_TAP"TRUE";
"B \NAC \NWC"6;
"S \NAC"
BN"6"51;
%"TAP"
"1","(2600,1550)","2","standard","I331";
;
CDS_LIB"standard"
BODY_TYPE"PLUMBING"
HDL_TAP"TRUE";
"B \NAC \NWC"5;
"S \NAC"
BN"7"27;
%"TAP"
"1","(2850,1600)","2","standard","I332";
;
CDS_LIB"standard"
BODY_TYPE"PLUMBING"
HDL_TAP"TRUE";
"B \NAC \NWC"6;
"S \NAC"
BN"7"28;
%"Q_CAP_DIFFBUS"
"2","(3575,200)","2","pure_quanta","I333";
;
LOCATION"C836"
$SEC"1"
CDS_SEC"1"
VALUE"DIFF BUS_0.22UF"
PIN_NAMES_ROTATE"TRUE"
CDS_LIB"pure_quanta"
CDS_LMAN_SYM_OUTLINE"-25,50,25,-50"
VOLTAGE"6.3V"
MATERIAL"X6S"
PACK_TYPE"C0201"
TOLERANCE"20%"
PART_NUMBER"SP_CH4221MEE01"
LOCATION"C836";
"2"
$PN"2"55;
"1"
$PN"1"117;
%"Q_CAP_DIFFBUS"
"2","(3575,150)","2","pure_quanta","I334";
;
LOCATION"C837"
$SEC"1"
CDS_SEC"1"
VALUE"DIFF BUS_0.22UF"
PIN_NAMES_ROTATE"TRUE"
CDS_LIB"pure_quanta"
CDS_LMAN_SYM_OUTLINE"-25,50,25,-50"
VOLTAGE"6.3V"
MATERIAL"X6S"
PACK_TYPE"C0201"
TOLERANCE"20%"
PART_NUMBER"SP_CH4221MEE01"
LOCATION"C837";
"2"
$PN"2"59;
"1"
$PN"1"118;
%"Q_CAP_DIFFBUS"
"2","(3575,400)","2","pure_quanta","I335";
;
LOCATION"C834"
$SEC"1"
CDS_SEC"1"
VALUE"DIFF BUS_0.22UF"
PIN_NAMES_ROTATE"TRUE"
CDS_LMAN_SYM_OUTLINE"-25,50,25,-50"
CDS_LIB"pure_quanta"
VOLTAGE"6.3V"
MATERIAL"X6S"
PACK_TYPE"C0201"
TOLERANCE"20%"
PART_NUMBER"SP_CH4221MEE01"
LOCATION"C834";
"2"
$PN"2"54;
"1"
$PN"1"116;
%"Q_CAP_DIFFBUS"
"2","(3575,350)","2","pure_quanta","I336";
;
LOCATION"C835"
$SEC"1"
CDS_SEC"1"
VALUE"DIFF BUS_0.22UF"
PIN_NAMES_ROTATE"TRUE"
CDS_LIB"pure_quanta"
CDS_LMAN_SYM_OUTLINE"-25,50,25,-50"
VOLTAGE"6.3V"
MATERIAL"X6S"
PACK_TYPE"C0201"
TOLERANCE"20%"
PART_NUMBER"SP_CH4221MEE01"
LOCATION"C835";
"2"
$PN"2"58;
"1"
$PN"1"26;
%"Q_CAP_DIFFBUS"
"2","(3575,750)","2","pure_quanta","I337";
;
LOCATION"C831"
$SEC"1"
CDS_SEC"1"
VALUE"DIFF BUS_0.22UF"
PIN_NAMES_ROTATE"TRUE"
CDS_LMAN_SYM_OUTLINE"-25,50,25,-50"
CDS_LIB"pure_quanta"
VOLTAGE"6.3V"
MATERIAL"X6S"
PACK_TYPE"C0201"
TOLERANCE"20%"
PART_NUMBER"SP_CH4221MEE01"
LOCATION"C831";
"2"
$PN"2"56;
"1"
$PN"1"113;
%"Q_CAP_DIFFBUS"
"2","(3575,600)","2","pure_quanta","I338";
;
LOCATION"C832"
$SEC"1"
CDS_SEC"1"
VALUE"DIFF BUS_0.22UF"
PIN_NAMES_ROTATE"TRUE"
CDS_LIB"pure_quanta"
CDS_LMAN_SYM_OUTLINE"-25,50,25,-50"
VOLTAGE"6.3V"
MATERIAL"X6S"
PACK_TYPE"C0201"
TOLERANCE"20%"
PART_NUMBER"SP_CH4221MEE01"
LOCATION"C832";
"2"
$PN"2"131;
"1"
$PN"1"114;
%"Q_CAP_DIFFBUS"
"2","(3575,550)","2","pure_quanta","I339";
;
LOCATION"C833"
$SEC"1"
CDS_SEC"1"
VALUE"DIFF BUS_0.22UF"
PIN_NAMES_ROTATE"TRUE"
CDS_LIB"pure_quanta"
CDS_LMAN_SYM_OUTLINE"-25,50,25,-50"
VOLTAGE"6.3V"
MATERIAL"X6S"
PACK_TYPE"C0201"
TOLERANCE"20%"
PART_NUMBER"SP_CH4221MEE01"
LOCATION"C833";
"2"
$PN"2"130;
"1"
$PN"1"115;
%"Q_CAP_DIFFBUS"
"2","(3575,1000)","2","pure_quanta","I340";
;
LOCATION"C828"
$SEC"1"
CDS_SEC"1"
VALUE"DIFF BUS_0.22UF"
PIN_NAMES_ROTATE"TRUE"
CDS_LIB"pure_quanta"
CDS_LMAN_SYM_OUTLINE"-25,50,25,-50"
VOLTAGE"6.3V"
MATERIAL"X6S"
PACK_TYPE"C0201"
TOLERANCE"20%"
PART_NUMBER"SP_CH4221MEE01"
LOCATION"C828";
"2"
$PN"2"53;
"1"
$PN"1"39;
%"Q_CAP_DIFFBUS"
"2","(3575,800)","2","pure_quanta","I341";
;
LOCATION"C830"
$SEC"1"
CDS_SEC"1"
VALUE"DIFF BUS_0.22UF"
PIN_NAMES_ROTATE"TRUE"
CDS_LMAN_SYM_OUTLINE"-25,50,25,-50"
CDS_LIB"pure_quanta"
VOLTAGE"6.3V"
MATERIAL"X6S"
PACK_TYPE"C0201"
TOLERANCE"20%"
PART_NUMBER"SP_CH4221MEE01"
LOCATION"C830";
"2"
$PN"2"132;
"1"
$PN"1"112;
%"Q_CAP_DIFFBUS"
"2","(3575,950)","2","pure_quanta","I342";
;
LOCATION"C829"
$SEC"1"
CDS_SEC"1"
VALUE"DIFF BUS_0.22UF"
PIN_NAMES_ROTATE"TRUE"
CDS_LIB"pure_quanta"
CDS_LMAN_SYM_OUTLINE"-25,50,25,-50"
VOLTAGE"6.3V"
MATERIAL"X6S"
PACK_TYPE"C0201"
TOLERANCE"20%"
PART_NUMBER"SP_CH4221MEE01"
LOCATION"C829";
"2"
$PN"2"57;
"1"
$PN"1"30;
%"Q_CAP_DIFFBUS"
"2","(3575,1150)","2","pure_quanta","I343";
;
LOCATION"C827"
$SEC"1"
CDS_SEC"1"
VALUE"DIFF BUS_0.22UF"
PIN_NAMES_ROTATE"TRUE"
CDS_LIB"pure_quanta"
CDS_LMAN_SYM_OUTLINE"-25,50,25,-50"
VOLTAGE"6.3V"
MATERIAL"X6S"
PACK_TYPE"C0201"
TOLERANCE"20%"
PART_NUMBER"SP_CH4221MEE01"
LOCATION"C827";
"2"
$PN"2"133;
"1"
$PN"1"25;
%"Q_CAP_DIFFBUS"
"2","(3575,1200)","2","pure_quanta","I344";
;
LOCATION"C826"
$SEC"1"
CDS_SEC"1"
VALUE"DIFF BUS_0.22UF"
PIN_NAMES_ROTATE"TRUE"
CDS_LIB"pure_quanta"
CDS_LMAN_SYM_OUTLINE"-25,50,25,-50"
VOLTAGE"6.3V"
MATERIAL"X6S"
PACK_TYPE"C0201"
TOLERANCE"20%"
PART_NUMBER"SP_CH4221MEE01"
LOCATION"C826";
"2"
$PN"2"52;
"1"
$PN"1"29;
%"Q_CAP_DIFFBUS"
"2","(3575,1600)","2","pure_quanta","I345";
;
LOCATION"C822"
$SEC"1"
CDS_SEC"1"
VALUE"DIFF BUS_0.22UF"
PIN_NAMES_ROTATE"TRUE"
CDS_LMAN_SYM_OUTLINE"-25,50,25,-50"
CDS_LIB"pure_quanta"
VOLTAGE"6.3V"
MATERIAL"X6S"
PACK_TYPE"C0201"
TOLERANCE"20%"
PART_NUMBER"SP_CH4221MEE01"
LOCATION"C822";
"2"
$PN"2"28;
"1"
$PN"1"35;
%"Q_CAP_DIFFBUS"
"2","(3575,1550)","2","pure_quanta","I346";
;
LOCATION"C823"
$SEC"1"
CDS_SEC"1"
VALUE"DIFF BUS_0.22UF"
PIN_NAMES_ROTATE"TRUE"
CDS_LIB"pure_quanta"
CDS_LMAN_SYM_OUTLINE"-25,50,25,-50"
VOLTAGE"6.3V"
MATERIAL"X6S"
PACK_TYPE"C0201"
TOLERANCE"20%"
PART_NUMBER"SP_CH4221MEE01"
LOCATION"C823";
"2"
$PN"2"27;
"1"
$PN"1"36;
%"TAP"
"1","(2600,2125)","2","standard","I347";
;
CDS_LIB"standard"
BODY_TYPE"PLUMBING"
HDL_TAP"TRUE";
"B \NAC \NWC"4;
"S \NAC"
BN"8"138;
%"TAP"
"1","(2600,2325)","2","standard","I348";
;
CDS_LIB"standard"
BODY_TYPE"PLUMBING"
HDL_TAP"TRUE";
"B \NAC \NWC"4;
"S \NAC"
BN"9"135;
%"TAP"
"1","(2600,2525)","2","standard","I349";
;
CDS_LIB"standard"
BODY_TYPE"PLUMBING"
HDL_TAP"TRUE";
"B \NAC \NWC"4;
"S \NAC"
BN"10"50;
%"TAP"
"1","(2850,2175)","2","standard","I350";
;
CDS_LIB"standard"
BODY_TYPE"PLUMBING"
HDL_TAP"TRUE";
"B \NAC \NWC"3;
"S \NAC"
BN"8"139;
%"TAP"
"1","(2850,2375)","2","standard","I351";
;
CDS_LIB"standard"
BODY_TYPE"PLUMBING"
HDL_TAP"TRUE";
"B \NAC \NWC"3;
"S \NAC"
BN"9"49;
%"TAP"
"1","(2600,2725)","2","standard","I352";
;
CDS_LIB"standard"
BODY_TYPE"PLUMBING"
HDL_TAP"TRUE";
"B \NAC \NWC"4;
"S \NAC"
BN"11"136;
%"TAP"
"1","(2600,2925)","2","standard","I353";
;
CDS_LIB"standard"
BODY_TYPE"PLUMBING"
HDL_TAP"TRUE";
"B \NAC \NWC"4;
"S \NAC"
BN"12"48;
%"TAP"
"1","(2850,2575)","2","standard","I354";
;
CDS_LIB"standard"
BODY_TYPE"PLUMBING"
HDL_TAP"TRUE";
"B \NAC \NWC"3;
"S \NAC"
BN"10"46;
%"TAP"
"1","(2850,2775)","2","standard","I355";
;
CDS_LIB"standard"
BODY_TYPE"PLUMBING"
HDL_TAP"TRUE";
"B \NAC \NWC"3;
"S \NAC"
BN"11"47;
%"TAP"
"1","(2850,2975)","2","standard","I356";
;
CDS_LIB"standard"
BODY_TYPE"PLUMBING"
HDL_TAP"TRUE";
"B \NAC \NWC"3;
"S \NAC"
BN"12"45;
%"TAP"
"1","(2600,3125)","2","standard","I357";
;
CDS_LIB"standard"
BODY_TYPE"PLUMBING"
HDL_TAP"TRUE";
"B \NAC \NWC"4;
"S \NAC"
BN"13"137;
%"TAP"
"1","(2600,3325)","2","standard","I358";
;
CDS_LIB"standard"
BODY_TYPE"PLUMBING"
HDL_TAP"TRUE";
"B \NAC \NWC"4;
"S \NAC"
BN"14"44;
%"TAP"
"1","(2600,3525)","2","standard","I359";
;
CDS_LIB"standard"
BODY_TYPE"PLUMBING"
HDL_TAP"TRUE";
"B \NAC \NWC"4;
"S \NAC"
BN"15"43;
%"TAP"
"1","(2850,3175)","2","standard","I360";
;
CDS_LIB"standard"
BODY_TYPE"PLUMBING"
HDL_TAP"TRUE";
"B \NAC \NWC"3;
"S \NAC"
BN"13"42;
%"TAP"
"1","(2850,3375)","2","standard","I361";
;
CDS_LIB"standard"
BODY_TYPE"PLUMBING"
HDL_TAP"TRUE";
"B \NAC \NWC"3;
"S \NAC"
BN"14"41;
%"TAP"
"1","(2850,3575)","2","standard","I362";
;
CDS_LIB"standard"
BODY_TYPE"PLUMBING"
HDL_TAP"TRUE";
"B \NAC \NWC"3;
"S \NAC"
BN"15"40;
%"Q_CAP_DIFFBUS"
"2","(3575,2175)","2","pure_quanta","I363";
;
LOCATION"C820"
$SEC"1"
CDS_SEC"1"
VALUE"DIFF BUS_0.22UF"
CDS_LMAN_SYM_OUTLINE"-25,50,25,-50"
CDS_LIB"pure_quanta"
PIN_NAMES_ROTATE"TRUE"
VOLTAGE"6.3V"
MATERIAL"X6S"
PACK_TYPE"C0201"
TOLERANCE"20%"
PART_NUMBER"SP_CH4221MEE01"
LOCATION"C820";
"2"
$PN"2"139;
"1"
$PN"1"144;
%"Q_CAP_DIFFBUS"
"2","(3575,2125)","2","pure_quanta","I364";
;
LOCATION"C821"
$SEC"1"
CDS_SEC"1"
VALUE"DIFF BUS_0.22UF"
CDS_LMAN_SYM_OUTLINE"-25,50,25,-50"
CDS_LIB"pure_quanta"
PIN_NAMES_ROTATE"TRUE"
VOLTAGE"6.3V"
MATERIAL"X6S"
PACK_TYPE"C0201"
TOLERANCE"20%"
PART_NUMBER"SP_CH4221MEE01"
LOCATION"C821";
"2"
$PN"2"138;
"1"
$PN"1"24;
%"Q_CAP_DIFFBUS"
"2","(3575,2375)","2","pure_quanta","I365";
;
LOCATION"C818"
$SEC"1"
CDS_SEC"1"
VALUE"DIFF BUS_0.22UF"
CDS_LIB"pure_quanta"
CDS_LMAN_SYM_OUTLINE"-25,50,25,-50"
PIN_NAMES_ROTATE"TRUE"
VOLTAGE"6.3V"
MATERIAL"X6S"
PACK_TYPE"C0201"
TOLERANCE"20%"
PART_NUMBER"SP_CH4221MEE01"
LOCATION"C818";
"2"
$PN"2"49;
"1"
$PN"1"140;
%"Q_CAP_DIFFBUS"
"2","(3575,2325)","2","pure_quanta","I366";
;
LOCATION"C819"
$SEC"1"
CDS_SEC"1"
VALUE"DIFF BUS_0.22UF"
CDS_LMAN_SYM_OUTLINE"-25,50,25,-50"
CDS_LIB"pure_quanta"
PIN_NAMES_ROTATE"TRUE"
VOLTAGE"6.3V"
MATERIAL"X6S"
PACK_TYPE"C0201"
TOLERANCE"20%"
PART_NUMBER"SP_CH4221MEE01"
LOCATION"C819";
"2"
$PN"2"135;
"1"
$PN"1"23;
%"Q_CAP_DIFFBUS"
"2","(3575,2525)","2","pure_quanta","I367";
;
LOCATION"C817"
$SEC"1"
CDS_SEC"1"
VALUE"DIFF BUS_0.22UF"
CDS_LMAN_SYM_OUTLINE"-25,50,25,-50"
CDS_LIB"pure_quanta"
PIN_NAMES_ROTATE"TRUE"
VOLTAGE"6.3V"
MATERIAL"X6S"
PACK_TYPE"C0201"
TOLERANCE"20%"
PART_NUMBER"SP_CH4221MEE01"
LOCATION"C817";
"2"
$PN"2"50;
"1"
$PN"1"141;
%"Q_CAP_DIFFBUS"
"2","(3575,2575)","2","pure_quanta","I368";
;
LOCATION"C816"
$SEC"1"
CDS_SEC"1"
VALUE"DIFF BUS_0.22UF"
CDS_LMAN_SYM_OUTLINE"-25,50,25,-50"
CDS_LIB"pure_quanta"
PIN_NAMES_ROTATE"TRUE"
VOLTAGE"6.3V"
MATERIAL"X6S"
PACK_TYPE"C0201"
TOLERANCE"20%"
PART_NUMBER"SP_CH4221MEE01"
LOCATION"C816";
"2"
$PN"2"46;
"1"
$PN"1"142;
%"Q_CAP_DIFFBUS"
"2","(3575,2725)","2","pure_quanta","I369";
;
LOCATION"C815"
$SEC"1"
CDS_SEC"1"
VALUE"DIFF BUS_0.22UF"
CDS_LIB"pure_quanta"
CDS_LMAN_SYM_OUTLINE"-25,50,25,-50"
PIN_NAMES_ROTATE"TRUE"
VOLTAGE"6.3V"
MATERIAL"X6S"
PACK_TYPE"C0201"
TOLERANCE"20%"
PART_NUMBER"SP_CH4221MEE01"
LOCATION"C815";
"2"
$PN"2"136;
"1"
$PN"1"143;
%"Q_CAP_DIFFBUS"
"2","(3575,2775)","2","pure_quanta","I370";
;
LOCATION"C814"
$SEC"1"
CDS_SEC"1"
VALUE"DIFF BUS_0.22UF"
CDS_LIB"pure_quanta"
CDS_LMAN_SYM_OUTLINE"-25,50,25,-50"
PIN_NAMES_ROTATE"TRUE"
VOLTAGE"6.3V"
MATERIAL"X6S"
PACK_TYPE"C0201"
TOLERANCE"20%"
PART_NUMBER"SP_CH4221MEE01"
LOCATION"C814";
"2"
$PN"2"47;
"1"
$PN"1"22;
%"Q_CAP_DIFFBUS"
"2","(3575,2975)","2","pure_quanta","I371";
;
LOCATION"C812"
$SEC"1"
CDS_SEC"1"
VALUE"DIFF BUS_0.22UF"
CDS_LMAN_SYM_OUTLINE"-25,50,25,-50"
CDS_LIB"pure_quanta"
PIN_NAMES_ROTATE"TRUE"
VOLTAGE"6.3V"
MATERIAL"X6S"
PACK_TYPE"C0201"
TOLERANCE"20%"
PART_NUMBER"SP_CH4221MEE01"
LOCATION"C812";
"2"
$PN"2"45;
"1"
$PN"1"21;
%"Q_CAP_DIFFBUS"
"2","(3575,2925)","2","pure_quanta","I372";
;
LOCATION"C813"
$SEC"1"
CDS_SEC"1"
VALUE"DIFF BUS_0.22UF"
CDS_LMAN_SYM_OUTLINE"-25,50,25,-50"
CDS_LIB"pure_quanta"
PIN_NAMES_ROTATE"TRUE"
VOLTAGE"6.3V"
MATERIAL"X6S"
PACK_TYPE"C0201"
TOLERANCE"20%"
PART_NUMBER"SP_CH4221MEE01"
LOCATION"C813";
"2"
$PN"2"48;
"1"
$PN"1"34;
%"Q_CAP_DIFFBUS"
"2","(3575,3125)","2","pure_quanta","I373";
;
LOCATION"C811"
$SEC"1"
CDS_SEC"1"
VALUE"DIFF BUS_0.22UF"
CDS_LMAN_SYM_OUTLINE"-25,50,25,-50"
CDS_LIB"pure_quanta"
PIN_NAMES_ROTATE"TRUE"
VOLTAGE"6.3V"
MATERIAL"X6S"
PACK_TYPE"C0201"
TOLERANCE"20%"
PART_NUMBER"SP_CH4221MEE01"
LOCATION"C811";
"2"
$PN"2"137;
"1"
$PN"1"20;
%"Q_CAP_DIFFBUS"
"2","(3575,3175)","2","pure_quanta","I374";
;
LOCATION"C810"
$SEC"1"
CDS_SEC"1"
VALUE"DIFF BUS_0.22UF"
CDS_LMAN_SYM_OUTLINE"-25,50,25,-50"
CDS_LIB"pure_quanta"
PIN_NAMES_ROTATE"TRUE"
VOLTAGE"6.3V"
MATERIAL"X6S"
PACK_TYPE"C0201"
TOLERANCE"20%"
PART_NUMBER"SP_CH4221MEE01"
LOCATION"C810";
"2"
$PN"2"42;
"1"
$PN"1"33;
%"Q_CAP_DIFFBUS"
"2","(3575,3325)","2","pure_quanta","I375";
;
LOCATION"C809"
$SEC"1"
CDS_SEC"1"
VALUE"DIFF BUS_0.22UF"
CDS_LMAN_SYM_OUTLINE"-25,50,25,-50"
CDS_LIB"pure_quanta"
PIN_NAMES_ROTATE"TRUE"
VOLTAGE"6.3V"
MATERIAL"X6S"
PACK_TYPE"C0201"
TOLERANCE"20%"
PART_NUMBER"SP_CH4221MEE01"
LOCATION"C809";
"2"
$PN"2"44;
"1"
$PN"1"19;
%"Q_CAP_DIFFBUS"
"2","(3575,3375)","2","pure_quanta","I376";
;
LOCATION"C808"
$SEC"1"
CDS_SEC"1"
VALUE"DIFF BUS_0.22UF"
CDS_LMAN_SYM_OUTLINE"-25,50,25,-50"
CDS_LIB"pure_quanta"
PIN_NAMES_ROTATE"TRUE"
VOLTAGE"6.3V"
MATERIAL"X6S"
PACK_TYPE"C0201"
TOLERANCE"20%"
PART_NUMBER"SP_CH4221MEE01"
LOCATION"C808";
"2"
$PN"2"41;
"1"
$PN"1"32;
%"Q_CAP_DIFFBUS"
"2","(3575,3575)","2","pure_quanta","I377";
;
LOCATION"C806"
$SEC"1"
CDS_SEC"1"
VALUE"DIFF BUS_0.22UF"
MATERIAL"X6S"
PACK_TYPE"C0201"
VOLTAGE"6.3V"
TOLERANCE"20%"
CDS_LIB"pure_quanta"
CDS_LMAN_SYM_OUTLINE"-25,50,25,-50"
PIN_NAMES_ROTATE"TRUE"
PART_NUMBER"SP_CH4221MEE01"
LOCATION"C806";
"2"
$PN"2"40;
"1"
$PN"1"31;
%"Q_CAP_DIFFBUS"
"2","(3575,3525)","2","pure_quanta","I378";
;
LOCATION"C807"
$SEC"1"
CDS_SEC"1"
VALUE"DIFF BUS_0.22UF"
CDS_LMAN_SYM_OUTLINE"-25,50,25,-50"
CDS_LIB"pure_quanta"
PIN_NAMES_ROTATE"TRUE"
VOLTAGE"6.3V"
MATERIAL"X6S"
PACK_TYPE"C0201"
TOLERANCE"20%"
PART_NUMBER"SP_CH4221MEE01"
LOCATION"C807";
"2"
$PN"2"43;
"1"
$PN"1"18;
%"TAP"
"1","(4125,200)","0","standard","I379";
;
CDS_LIB"standard"
BODY_TYPE"PLUMBING"
HDL_TAP"TRUE";
"B \NAC \NWC"11;
"S \NAC"
BN"0"117;
%"TAP"
"1","(4325,150)","0","standard","I380";
;
CDS_LIB"standard"
BODY_TYPE"PLUMBING"
HDL_TAP"TRUE";
"B \NAC \NWC"10;
"S \NAC"
BN"0"118;
%"TAP"
"1","(4125,400)","0","standard","I381";
;
CDS_LIB"standard"
BODY_TYPE"PLUMBING"
HDL_TAP"TRUE";
"B \NAC \NWC"11;
"S \NAC"
BN"1"116;
%"TAP"
"1","(4325,350)","0","standard","I382";
;
CDS_LIB"standard"
BODY_TYPE"PLUMBING"
HDL_TAP"TRUE";
"B \NAC \NWC"10;
"S \NAC"
BN"1"26;
%"TAP"
"1","(4125,600)","0","standard","I383";
;
CDS_LIB"standard"
BODY_TYPE"PLUMBING"
HDL_TAP"TRUE";
"B \NAC \NWC"11;
"S \NAC"
BN"2"114;
%"TAP"
"1","(4325,550)","0","standard","I384";
;
CDS_LIB"standard"
BODY_TYPE"PLUMBING"
HDL_TAP"TRUE";
"B \NAC \NWC"10;
"S \NAC"
BN"2"115;
%"TAP"
"1","(4325,750)","0","standard","I385";
;
CDS_LIB"standard"
BODY_TYPE"PLUMBING"
HDL_TAP"TRUE";
"B \NAC \NWC"10;
"S \NAC"
BN"3"113;
%"TAP"
"1","(4125,800)","0","standard","I386";
;
CDS_LIB"standard"
BODY_TYPE"PLUMBING"
HDL_TAP"TRUE";
"B \NAC \NWC"11;
"S \NAC"
BN"3"112;
%"TAP"
"1","(4325,950)","0","standard","I387";
;
CDS_LIB"standard"
BODY_TYPE"PLUMBING"
HDL_TAP"TRUE";
"B \NAC \NWC"10;
"S \NAC"
BN"4"30;
%"TAP"
"1","(4125,1200)","0","standard","I388";
;
CDS_LIB"standard"
BODY_TYPE"PLUMBING"
HDL_TAP"TRUE";
"B \NAC \NWC"11;
"S \NAC"
BN"5"29;
%"TAP"
"1","(4325,1150)","0","standard","I389";
;
CDS_LIB"standard"
BODY_TYPE"PLUMBING"
HDL_TAP"TRUE";
"B \NAC \NWC"10;
"S \NAC"
BN"5"25;
%"TAP"
"1","(4125,1400)","0","standard","I390";
;
CDS_LIB"standard"
BODY_TYPE"PLUMBING"
HDL_TAP"TRUE";
"B \NAC \NWC"11;
"S \NAC"
BN"6"38;
%"TAP"
"1","(4325,1350)","0","standard","I391";
;
CDS_LIB"standard"
BODY_TYPE"PLUMBING"
HDL_TAP"TRUE";
"B \NAC \NWC"10;
"S \NAC"
BN"6"37;
%"TAP"
"1","(4125,1600)","0","standard","I392";
;
CDS_LIB"standard"
BODY_TYPE"PLUMBING"
HDL_TAP"TRUE";
"B \NAC \NWC"11;
"S \NAC"
BN"7"35;
%"TAP"
"1","(4325,1550)","0","standard","I393";
;
CDS_LIB"standard"
BODY_TYPE"PLUMBING"
HDL_TAP"TRUE";
"B \NAC \NWC"10;
"S \NAC"
BN"7"36;
%"TAP"
"1","(4125,2175)","0","standard","I396";
;
CDS_LIB"standard"
BODY_TYPE"PLUMBING"
HDL_TAP"TRUE";
"B \NAC \NWC"1;
"S \NAC"
BN"8"144;
%"TAP"
"1","(4325,2125)","0","standard","I397";
;
CDS_LIB"standard"
BODY_TYPE"PLUMBING"
HDL_TAP"TRUE";
"B \NAC \NWC"2;
"S \NAC"
BN"8"24;
%"TAP"
"1","(4125,2375)","0","standard","I398";
;
CDS_LIB"standard"
BODY_TYPE"PLUMBING"
HDL_TAP"TRUE";
"B \NAC \NWC"1;
"S \NAC"
BN"9"140;
%"TAP"
"1","(4325,2525)","0","standard","I399";
;
CDS_LIB"standard"
BODY_TYPE"PLUMBING"
HDL_TAP"TRUE";
"B \NAC \NWC"2;
"S \NAC"
BN"10"141;
%"TAP"
"1","(4325,2325)","0","standard","I400";
;
CDS_LIB"standard"
BODY_TYPE"PLUMBING"
HDL_TAP"TRUE";
"B \NAC \NWC"2;
"S \NAC"
BN"9"23;
%"TAP"
"1","(4125,2575)","0","standard","I401";
;
CDS_LIB"standard"
BODY_TYPE"PLUMBING"
HDL_TAP"TRUE";
"B \NAC \NWC"1;
"S \NAC"
BN"10"142;
%"TAP"
"1","(4125,2775)","0","standard","I402";
;
CDS_LIB"standard"
BODY_TYPE"PLUMBING"
HDL_TAP"TRUE";
"B \NAC \NWC"1;
"S \NAC"
BN"11"22;
%"TAP"
"1","(4325,2725)","0","standard","I403";
;
CDS_LIB"standard"
BODY_TYPE"PLUMBING"
HDL_TAP"TRUE";
"B \NAC \NWC"2;
"S \NAC"
BN"11"143;
%"TAP"
"1","(4125,2975)","0","standard","I404";
;
CDS_LIB"standard"
BODY_TYPE"PLUMBING"
HDL_TAP"TRUE";
"B \NAC \NWC"1;
"S \NAC"
BN"12"21;
%"TAP"
"1","(4325,2925)","0","standard","I405";
;
CDS_LIB"standard"
BODY_TYPE"PLUMBING"
HDL_TAP"TRUE";
"B \NAC \NWC"2;
"S \NAC"
BN"12"34;
%"TAP"
"1","(4125,3175)","0","standard","I406";
;
CDS_LIB"standard"
BODY_TYPE"PLUMBING"
HDL_TAP"TRUE";
"B \NAC \NWC"1;
"S \NAC"
BN"13"33;
%"TAP"
"1","(4325,3125)","0","standard","I407";
;
CDS_LIB"standard"
BODY_TYPE"PLUMBING"
HDL_TAP"TRUE";
"B \NAC \NWC"2;
"S \NAC"
BN"13"20;
%"TAP"
"1","(4325,3325)","0","standard","I408";
;
CDS_LIB"standard"
BODY_TYPE"PLUMBING"
HDL_TAP"TRUE";
"B \NAC \NWC"2;
"S \NAC"
BN"14"19;
%"TAP"
"1","(4125,3575)","0","standard","I409";
;
CDS_LIB"standard"
BODY_TYPE"PLUMBING"
HDL_TAP"TRUE";
"B \NAC \NWC"1;
"S \NAC"
BN"15"31;
%"TAP"
"1","(4125,3375)","0","standard","I410";
;
CDS_LIB"standard"
BODY_TYPE"PLUMBING"
HDL_TAP"TRUE";
"B \NAC \NWC"1;
"S \NAC"
BN"14"32;
%"TAP"
"1","(4325,3525)","0","standard","I411";
;
CDS_LIB"standard"
BODY_TYPE"PLUMBING"
HDL_TAP"TRUE";
"B \NAC \NWC"2;
"S \NAC"
BN"15"18;
%"TAP"
"1","(4125,1000)","0","standard","I414";
;
CDS_LIB"standard"
BODY_TYPE"PLUMBING"
HDL_TAP"TRUE";
"B \NAC \NWC"11;
"S \NAC"
BN"4"39;
%"Q_CAP_DIFFBUS"
"2","(3575,1350)","2","pure_quanta","I415";
;
LOCATION"C825"
$SEC"1"
CDS_SEC"1"
VALUE"DIFF BUS_0.22UF"
PIN_NAMES_ROTATE"TRUE"
CDS_LIB"pure_quanta"
CDS_LMAN_SYM_OUTLINE"-25,50,25,-50"
VOLTAGE"6.3V"
MATERIAL"X6S"
PACK_TYPE"C0201"
TOLERANCE"20%"
PART_NUMBER"SP_CH4221MEE01"
LOCATION"C825";
"2"
$PN"2"134;
"1"
$PN"1"37;
%"Q_CAP_DIFFBUS"
"2","(3575,1400)","2","pure_quanta","I416";
;
LOCATION"C824"
$SEC"1"
CDS_SEC"1"
VALUE"DIFF BUS_0.22UF"
PIN_NAMES_ROTATE"TRUE"
CDS_LIB"pure_quanta"
CDS_LMAN_SYM_OUTLINE"-25,50,25,-50"
VOLTAGE"6.3V"
MATERIAL"X6S"
PACK_TYPE"C0201"
TOLERANCE"20%"
PART_NUMBER"SP_CH4221MEE01"
LOCATION"C824";
"2"
$PN"2"51;
"1"
$PN"1"38;
END.
